(kicad_pcb
	(version 20240108)
	(generator "pcbnew")
	(generator_version "8.0")
	(general
		(thickness 1.62)
		(legacy_teardrops no)
	)
	(paper "A4")
	(title_block
		(title "Jetson Orin Baseboard")
		(date "2025-03-12")
		(rev "1.3.4")
		(company "Antmicro Ltd")
		(comment 1 "www.antmicro.com")
		(comment 9 "footprints 497-499 of 677")
	)
	(layers
		(0 "F.Cu" signal)
		(1 "In1.Cu" signal)
		(2 "In2.Cu" signal)
		(3 "In3.Cu" signal)
		(4 "In4.Cu" jumper)
		(5 "In5.Cu" signal)
		(6 "In6.Cu" signal)
		(31 "B.Cu" signal)
		(32 "B.Adhes" user "B.Adhesive")
		(33 "F.Adhes" user "F.Adhesive")
		(34 "B.Paste" user)
		(35 "F.Paste" user)
		(36 "B.SilkS" user "B.Silkscreen")
		(37 "F.SilkS" user "F.Silkscreen")
		(38 "B.Mask" user)
		(39 "F.Mask" user)
		(40 "Dwgs.User" user "User.Drawings")
		(41 "Cmts.User" user "User.Comments")
		(42 "Eco1.User" user "User.Eco1")
		(43 "Eco2.User" user "User.Eco2")
		(44 "Edge.Cuts" user)
		(45 "Margin" user)
		(46 "B.CrtYd" user "B.Courtyard")
		(47 "F.CrtYd" user "F.Courtyard")
		(48 "B.Fab" user)
		(49 "F.Fab" user)
	)
	(footprint "antmicro-footprints:R_Array_4x0201_Panasonic_EXB18V"
		(layer "B.Cu")
		(at 85.21 122.08 180)
		(property "Reference" "R112"
			(at 0.91 0.68 0)
			(layer "B.SilkS")
			(effects
				(font
					(size 0.7 0.7)
					(thickness 0.15)
				)
				(justify right bottom mirror)
			)
		)
		(property "Value" "R_4x100R_0201_array"
			(at -1.1 -1.8 0)
			(layer "B.Fab")
			(effects
				(font
					(size 0.7 0.7)
					(thickness 0.15)
				)
				(justify left bottom mirror)
			)
		)
		(property "Footprint" "antmicro-footprints:R_Array_4x0201_Panasonic_EXB18V"
			(at 0 0 180)
			(layer "F.Fab")
			(hide yes)
			(effects
				(font
					(size 1.27 1.27)
					(thickness 0.15)
				)
			)
		)
		(property "Datasheet" "http://industrial.panasonic.com/cdbs/www-data/pdf/AOC0000/AOC0000C14.pdf"
			(at 0 0 180)
			(layer "F.Fab")
			(hide yes)
			(effects
				(font
					(size 1.27 1.27)
					(thickness 0.15)
				)
			)
		)
		(property "Author" "Antmicro"
			(at 170.42 244.16 0)
			(layer "B.Fab")
			(hide yes)
			(effects
				(font
					(size 1 1)
					(thickness 0.15)
				)
				(justify mirror)
			)
		)
		(property "License" "Apache-2.0"
			(at 170.42 244.16 0)
			(layer "B.Fab")
			(hide yes)
			(effects
				(font
					(size 1 1)
					(thickness 0.15)
				)
				(justify mirror)
			)
		)
		(property "MPN" "EXB-18V101JX"
			(at 170.42 244.16 0)
			(layer "B.Fab")
			(hide yes)
			(effects
				(font
					(size 1 1)
					(thickness 0.15)
				)
				(justify mirror)
			)
		)
		(property "Manufacturer" "Panasonic"
			(at 170.42 244.16 0)
			(layer "B.Fab")
			(hide yes)
			(effects
				(font
					(size 1 1)
					(thickness 0.15)
				)
				(justify mirror)
			)
		)
		(property "Val" "R_4x100R_0201"
			(at 170.42 244.16 0)
			(layer "B.Fab")
			(hide yes)
			(effects
				(font
					(size 1 1)
					(thickness 0.15)
				)
				(justify mirror)
			)
		)
		(sheetname "Peripherals")
		(sheetfile "peripherals.kicad_sch")
		(attr smd exclude_from_pos_files exclude_from_bom dnp)
		(fp_line
			(start 0.8 -0.45)
			(end 0.8 0.45)
			(stroke
				(width 0.12)
				(type solid)
			)
			(layer "B.SilkS")
		)
		(fp_line
			(start -0.8 -0.45)
			(end -0.8 0.45)
			(stroke
				(width 0.12)
				(type solid)
			)
			(layer "B.SilkS")
		)
		(fp_rect
			(start -0.898 0.66)
			(end 0.898 -0.65)
			(stroke
				(width 0.05)
				(type solid)
			)
			(fill none)
			(layer "B.CrtYd")
		)
		(fp_text user "Author: Antmicro"
			(at -1.051 -4.599 0)
			(layer "B.Fab")
			(hide yes)
			(effects
				(font
					(size 0.7 0.7)
					(thickness 0.15)
				)
				(justify left bottom mirror)
			)
		)
		(fp_text user "${REFERENCE}"
			(at -1.051 -3.2 0)
			(layer "B.Fab")
			(hide yes)
			(effects
				(font
					(size 0.7 0.7)
					(thickness 0.15)
				)
				(justify left bottom mirror)
			)
		)
		(fp_text user "License: Apache-2.0"
			(at -1.051 -6 0)
			(layer "B.Fab")
			(hide yes)
			(effects
				(font
					(size 0.7 0.7)
					(thickness 0.15)
				)
				(justify left bottom mirror)
			)
		)
		(pad "1" smd roundrect
			(at -0.6 -0.298 180)
			(size 0.2 0.4)
			(layers "B.Cu" "B.Paste" "B.Mask")
			(roundrect_rratio 0.25)
			(net 779 "Net-(D63-A)")
			(pinfunction "R1.1")
			(pintype "passive")
		)
		(pad "2" smd roundrect
			(at -0.202 -0.298 180)
			(size 0.2 0.4)
			(layers "B.Cu" "B.Paste" "B.Mask")
			(roundrect_rratio 0.25)
			(net 773 "/Peripherals/MISO")
			(pinfunction "R2.1")
			(pintype "passive")
		)
		(pad "3" smd roundrect
			(at 0.2 -0.298 180)
			(size 0.2 0.4)
			(layers "B.Cu" "B.Paste" "B.Mask")
			(roundrect_rratio 0.25)
			(net 774 "/Peripherals/MOSI")
			(pinfunction "R3.1")
			(pintype "passive")
		)
		(pad "4" smd roundrect
			(at 0.598 -0.298 180)
			(size 0.2 0.4)
			(layers "B.Cu" "B.Paste" "B.Mask")
			(roundrect_rratio 0.25)
			(net 777 "unconnected-(R112-R4.1-Pad4)")
			(pinfunction "R4.1")
			(pintype "passive+no_connect")
		)
		(pad "5" smd roundrect
			(at 0.598 0.3 180)
			(size 0.2 0.4)
			(layers "B.Cu" "B.Paste" "B.Mask")
			(roundrect_rratio 0.25)
			(net 778 "unconnected-(R112-R4.2-Pad5)")
			(pinfunction "R4.2")
			(pintype "passive+no_connect")
		)
		(pad "6" smd roundrect
			(at 0.2 0.3 180)
			(size 0.2 0.4)
			(layers "B.Cu" "B.Paste" "B.Mask")
			(roundrect_rratio 0.25)
			(net 251 "SYS_SDA")
			(pinfunction "R3.2")
			(pintype "passive")
		)
		(pad "7" smd roundrect
			(at -0.202 0.3 180)
			(size 0.2 0.4)
			(layers "B.Cu" "B.Paste" "B.Mask")
			(roundrect_rratio 0.25)
			(net 251 "SYS_SDA")
			(pinfunction "R2.2")
			(pintype "passive")
		)
		(pad "8" smd roundrect
			(at -0.6 0.3 180)
			(size 0.2 0.4)
			(layers "B.Cu" "B.Paste" "B.Mask")
			(roundrect_rratio 0.25)
			(net 252 "SYS_SCL")
			(pinfunction "R1.2")
			(pintype "passive")
		)
	)
	(footprint "antmicro-footprints:TP_SMD_0.75mm"
		(layer "B.Cu")
		(at 102.14999 103.5508 180)
		(property "Reference" "TP39"
			(at 0 0.6 0)
			(layer "B.SilkS")
			(hide yes)
			(effects
				(font
					(size 0.7 0.7)
					(thickness 0.15)
				)
				(justify left bottom mirror)
			)
		)
		(property "Value" "TP_0.75mm_SMD"
			(at 0 -1.2 0)
			(layer "B.Fab")
			(effects
				(font
					(size 0.7 0.7)
					(thickness 0.15)
				)
				(justify left bottom mirror)
			)
		)
		(property "Footprint" "antmicro-footprints:TP_SMD_0.75mm"
			(at 0 0 180)
			(layer "F.Fab")
			(hide yes)
			(effects
				(font
					(size 1.27 1.27)
					(thickness 0.15)
				)
			)
		)
		(property "Author" "Antmicro"
			(at 204.29998 207.1016 0)
			(layer "B.Fab")
			(hide yes)
			(effects
				(font
					(size 1 1)
					(thickness 0.15)
				)
				(justify mirror)
			)
		)
		(property "License" "Apache-2.0"
			(at 204.29998 207.1016 0)
			(layer "B.Fab")
			(hide yes)
			(effects
				(font
					(size 1 1)
					(thickness 0.15)
				)
				(justify mirror)
			)
		)
		(property "MPN" ""
			(at 204.29998 207.1016 0)
			(layer "B.Fab")
			(hide yes)
			(effects
				(font
					(size 1 1)
					(thickness 0.15)
				)
				(justify mirror)
			)
		)
		(property "Manufacturer" ""
			(at 204.29998 207.1016 0)
			(layer "B.Fab")
			(hide yes)
			(effects
				(font
					(size 1 1)
					(thickness 0.15)
				)
				(justify mirror)
			)
		)
		(sheetname "CSI")
		(sheetfile "csi.kicad_sch")
		(attr exclude_from_pos_files exclude_from_bom)
		(fp_circle
			(center 0 0)
			(end 0.475 0)
			(stroke
				(width 0.05)
				(type default)
			)
			(fill none)
			(layer "B.CrtYd")
		)
		(fp_text user "${REFERENCE}"
			(at -0.4 -2.7 0)
			(layer "B.Fab")
			(hide yes)
			(effects
				(font
					(size 0.7 0.7)
					(thickness 0.15)
				)
				(justify left bottom mirror)
			)
		)
		(fp_text user "License: Apache-2.0"
			(at -0.4 -5.101 0)
			(layer "B.Fab")
			(hide yes)
			(effects
				(font
					(size 0.7 0.7)
					(thickness 0.15)
				)
				(justify left bottom mirror)
			)
		)
		(fp_text user "Author: Antmicro"
			(at -0.4 -3.901 0)
			(layer "B.Fab")
			(hide yes)
			(effects
				(font
					(size 0.7 0.7)
					(thickness 0.15)
				)
				(justify left bottom mirror)
			)
		)
		(pad "1" smd circle
			(at 0 0 180)
			(size 0.75 0.75)
			(layers "B.Cu" "B.Mask")
			(net 538 "/CSI/MUX_I2C_5_SCL")
			(pinfunction "1")
			(pintype "passive")
		)
	)
	(footprint "antmicro-footprints:USB-C_Receptacle_GCT_USB4105-GF-A"
		(layer "B.Cu")
		(at 53.59 124.74 180)
		(property "Reference" "J3"
			(at -7.61 2.49 0)
			(layer "B.SilkS")
			(effects
				(font
					(size 0.7 0.7)
					(thickness 0.15)
				)
				(justify left bottom mirror)
			)
		)
		(property "Value" "USB-C_GCT_USB4105-GF-A"
			(at 0 -5 0)
			(layer "B.Fab")
			(effects
				(font
					(size 0.7 0.7)
					(thickness 0.15)
				)
				(justify left bottom mirror)
			)
		)
		(property "Footprint" "antmicro-footprints:USB-C_Receptacle_GCT_USB4105-GF-A"
			(at 0 0 180)
			(layer "F.Fab")
			(hide yes)
			(effects
				(font
					(size 1.27 1.27)
					(thickness 0.15)
				)
			)
		)
		(property "Datasheet" "https://gct.co/files/drawings/usb4105.pdf"
			(at 0 0 180)
			(layer "F.Fab")
			(hide yes)
			(effects
				(font
					(size 1.27 1.27)
					(thickness 0.15)
				)
			)
		)
		(property "Author" "Antmicro"
			(at 107.18 249.48 0)
			(layer "B.Fab")
			(hide yes)
			(effects
				(font
					(size 1 1)
					(thickness 0.15)
				)
				(justify mirror)
			)
		)
		(property "License" "Apache-2.0"
			(at 107.18 249.48 0)
			(layer "B.Fab")
			(hide yes)
			(effects
				(font
					(size 1 1)
					(thickness 0.15)
				)
				(justify mirror)
			)
		)
		(property "MPN" "USB4105-GF-A"
			(at 107.18 249.48 0)
			(layer "B.Fab")
			(hide yes)
			(effects
				(font
					(size 1 1)
					(thickness 0.15)
				)
				(justify mirror)
			)
		)
		(property "Manufacturer" "GCT"
			(at 107.18 249.48 0)
			(layer "B.Fab")
			(hide yes)
			(effects
				(font
					(size 1 1)
					(thickness 0.15)
				)
				(justify mirror)
			)
		)
		(sheetname "USB Debug, DP")
		(sheetfile "usb.kicad_sch")
		(attr smd)
		(fp_line
			(start 4.788 0.145)
			(end 4.788 1.395)
			(stroke
				(width 0.15)
				(type solid)
			)
			(layer "B.SilkS")
		)
		(fp_line
			(start 4.788 -2.575)
			(end 4.788 -3.854)
			(stroke
				(width 0.15)
				(type solid)
			)
			(layer "B.SilkS")
		)
		(fp_line
			(start 4.788 -3.854)
			(end -4.79 -3.854)
			(stroke
				(width 0.15)
				(type solid)
			)
			(layer "B.SilkS")
		)
		(fp_line
			(start -4.79 0.145)
			(end -4.79 1.395)
			(stroke
				(width 0.15)
				(type solid)
			)
			(layer "B.SilkS")
		)
		(fp_line
			(start -4.79 -3.854)
			(end -4.79 -2.575)
			(stroke
				(width 0.15)
				(type solid)
			)
			(layer "B.SilkS")
		)
		(fp_circle
			(center -3.8 4.27071)
			(end -3.75 4.22071)
			(stroke
				(width 0.15)
				(type solid)
			)
			(fill solid)
			(layer "B.SilkS")
		)
		(fp_rect
			(start -5.1 4.4)
			(end 5.1 -3.9)
			(stroke
				(width 0.05)
				(type solid)
			)
			(fill none)
			(layer "B.CrtYd")
		)
		(fp_line
			(start 4.788 3.676)
			(end -4.79 3.676)
			(stroke
				(width 0.15)
				(type solid)
			)
			(layer "B.Fab")
		)
		(fp_line
			(start 4.788 -3.854)
			(end 4.788 3.676)
			(stroke
				(width 0.15)
				(type solid)
			)
			(layer "B.Fab")
		)
		(fp_line
			(start 4.788 -3.854)
			(end -4.702 -3.854)
			(stroke
				(width 0.15)
				(type solid)
			)
			(layer "B.Fab")
		)
		(fp_line
			(start -4.79 3.676)
			(end -4.79 -3.854)
			(stroke
				(width 0.15)
				(type solid)
			)
			(layer "B.Fab")
		)
		(fp_line
			(start -4.79 -3.854)
			(end 4.788 -3.854)
			(stroke
				(width 0.15)
				(type solid)
			)
			(layer "B.Fab")
		)
		(fp_text user "${REFERENCE}"
			(at -4.79 -6.853 0)
			(layer "B.Fab")
			(hide yes)
			(effects
				(font
					(size 0.7 0.7)
					(thickness 0.15)
				)
				(justify left bottom mirror)
			)
		)
		(fp_text user "License: Apache-2.0"
			(at -4.79 -8.855 0)
			(layer "B.Fab")
			(hide yes)
			(effects
				(font
					(size 0.7 0.7)
					(thickness 0.15)
				)
				(justify left bottom mirror)
			)
		)
		(fp_text user "Author: Antmicro"
			(at -4.79 -7.853 0)
			(layer "B.Fab")
			(hide yes)
			(effects
				(font
					(size 0.7 0.7)
					(thickness 0.15)
				)
				(justify left bottom mirror)
			)
		)
		(fp_text user "PCB-EDGE"
			(at -4.79 -5.853 0)
			(layer "B.Fab")
			(hide yes)
			(effects
				(font
					(size 0.7 0.7)
					(thickness 0.15)
				)
				(justify left bottom mirror)
			)
		)
		(pad "" np_thru_hole circle
			(at -2.891 2.426 180)
			(size 0.65 0.65)
			(drill 0.65)
			(layers "*.Cu" "*.Mask")
		)
		(pad "" np_thru_hole circle
			(at 2.89 2.426 180)
			(size 0.65 0.65)
			(drill 0.65)
			(layers "*.Cu" "*.Mask")
		)
		(pad "A1" smd roundrect
			(at -3.202 3.5 180)
			(size 0.6 1.15)
			(layers "B.Cu" "B.Paste" "B.Mask")
			(roundrect_rratio 0.25)
			(net 1 "GND")
			(pinfunction "GND")
			(pintype "power_in")
		)
		(pad "A4" smd roundrect
			(at -2.4 3.5 180)
			(size 0.6 1.15)
			(layers "B.Cu" "B.Paste" "B.Mask")
			(roundrect_rratio 0.25)
			(net 196 "/USB Debug, DP/USBC3_VBUS")
			(pinfunction "VBUS")
			(pintype "passive")
		)
		(pad "A5" smd roundrect
			(at -1.25 3.5 180)
			(size 0.3 1.15)
			(layers "B.Cu" "B.Paste" "B.Mask")
			(roundrect_rratio 0.25)
			(net 273 "/USB Debug, DP/USBC3_CC1")
			(pinfunction "CC_{1}")
			(pintype "bidirectional")
		)
		(pad "A6" smd roundrect
			(at -0.25 3.5 180)
			(size 0.3 1.15)
			(layers "B.Cu" "B.Paste" "B.Mask")
			(roundrect_rratio 0.25)
			(net 613 "/USB Debug, DP/USBC3_D_P")
			(pinfunction "D_{A}+")
			(pintype "bidirectional")
		)
		(pad "A7" smd roundrect
			(at 0.248 3.5 180)
			(size 0.3 1.15)
			(layers "B.Cu" "B.Paste" "B.Mask")
			(roundrect_rratio 0.25)
			(net 275 "/USB Debug, DP/USBC3_D_N")
			(pinfunction "D_{A}-")
			(pintype "bidirectional")
		)
		(pad "A8" smd roundrect
			(at 1.249 3.5 180)
			(size 0.3 1.15)
			(layers "B.Cu" "B.Paste" "B.Mask")
			(roundrect_rratio 0.25)
			(net 533 "unconnected-(J3-SBU_{1}-PadA8)")
			(pinfunction "SBU_{1}")
			(pintype "bidirectional+no_connect")
		)
		(pad "A9" smd roundrect
			(at 2.398 3.5 180)
			(size 0.6 1.15)
			(layers "B.Cu" "B.Paste" "B.Mask")
			(roundrect_rratio 0.25)
			(net 196 "/USB Debug, DP/USBC3_VBUS")
			(pinfunction "VBUS")
			(pintype "passive")
		)
		(pad "A12" smd roundrect
			(at 3.2 3.5 180)
			(size 0.6 1.15)
			(layers "B.Cu" "B.Paste" "B.Mask")
			(roundrect_rratio 0.25)
			(net 1 "GND")
			(pinfunction "GND")
			(pintype "passive")
		)
		(pad "B1" smd roundrect
			(at 3.2 3.5 180)
			(size 0.6 1.15)
			(layers "B.Cu" "B.Paste" "B.Mask")
			(roundrect_rratio 0.25)
			(net 1 "GND")
			(pinfunction "GND")
			(pintype "passive")
		)
		(pad "B4" smd roundrect
			(at 2.398 3.5 180)
			(size 0.6 1.15)
			(layers "B.Cu" "B.Paste" "B.Mask")
			(roundrect_rratio 0.25)
			(net 196 "/USB Debug, DP/USBC3_VBUS")
			(pinfunction "VBUS")
			(pintype "passive")
		)
		(pad "B5" smd roundrect
			(at 1.749 3.5 180)
			(size 0.3 1.15)
			(layers "B.Cu" "B.Paste" "B.Mask")
			(roundrect_rratio 0.25)
			(net 276 "/USB Debug, DP/USBC3_CC2")
			(pinfunction "CC_{2}")
			(pintype "bidirectional")
		)
		(pad "B6" smd roundrect
			(at 0.748 3.5 180)
			(size 0.3 1.15)
			(layers "B.Cu" "B.Paste" "B.Mask")
			(roundrect_rratio 0.25)
			(net 613 "/USB Debug, DP/USBC3_D_P")
			(pinfunction "D_{B}+")
			(pintype "bidirectional")
		)
		(pad "B7" smd roundrect
			(at -0.75 3.5 180)
			(size 0.3 1.15)
			(layers "B.Cu" "B.Paste" "B.Mask")
			(roundrect_rratio 0.25)
			(net 275 "/USB Debug, DP/USBC3_D_N")
			(pinfunction "D_{B}-")
			(pintype "bidirectional")
		)
		(pad "B8" smd roundrect
			(at -1.75 3.5 180)
			(size 0.3 1.15)
			(layers "B.Cu" "B.Paste" "B.Mask")
			(roundrect_rratio 0.25)
			(net 547 "unconnected-(J3-SBU_{2}-PadB8)")
			(pinfunction "SBU_{2}")
			(pintype "bidirectional+no_connect")
		)
		(pad "B9" smd roundrect
			(at -2.4 3.5 180)
			(size 0.6 1.15)
			(layers "B.Cu" "B.Paste" "B.Mask")
			(roundrect_rratio 0.25)
			(net 196 "/USB Debug, DP/USBC3_VBUS")
			(pinfunction "VBUS")
			(pintype "passive")
		)
		(pad "B12" smd roundrect
			(at -3.202 3.5 180)
			(size 0.6 1.15)
			(layers "B.Cu" "B.Paste" "B.Mask")
			(roundrect_rratio 0.25)
			(net 1 "GND")
			(pinfunction "GND")
			(pintype "passive")
		)
		(pad "SH" thru_hole oval
			(at -4.321 -1.255 180)
			(size 1 2)
			(drill oval 0.6 1.4)
			(layers "*.Cu" "*.Mask")
			(remove_unused_layers no)
			(net 1 "GND")
			(pinfunction "SH")
			(pintype "passive")
		)
		(pad "SH" thru_hole oval
			(at -4.321 2.926 180)
			(size 1.05 2.1)
			(drill oval 0.6 1.7)
			(layers "*.Cu" "*.Mask")
			(remove_unused_layers no)
			(net 1 "GND")
			(pinfunction "SH")
			(pintype "passive")
		)
		(pad "SH" thru_hole oval
			(at 4.32 -1.255 180)
			(size 1 2)
			(drill oval 0.6 1.4)
			(layers "*.Cu" "*.Mask")
			(remove_unused_layers no)
			(net 1 "GND")
			(pinfunction "SH")
			(pintype "passive")
		)
		(pad "SH" thru_hole oval
			(at 4.32 2.926 180)
			(size 1.05 2.1)
			(drill oval 0.6 1.7)
			(layers "*.Cu" "*.Mask")
			(remove_unused_layers no)
			(net 1 "GND")
			(pinfunction "SH")
			(pintype "passive")
		)
	)
)
